FILE_TYPE = MULTI_PHYS_TABLE;

PART 'INA183A1IDBVR'

{========================================================================================}
:VALUE           | PART_TYPE | MATERIAL | PART_NUMBER    = STANDARD    | LIFECYCLE     | PART_NUMBER   | JEDEC_TYPE               | DESCRIPTION                       | MANUFTR | MANUF_PN        | RD_CMPLS_LVL | CMPLS_LVL | FROM_PJ    | CLASS | DIP_SMD | DATA                    | EE_CHECK_LIST | FP_ECN | PSL | CREATOR | STATUS | MSD  | ESD_CDM | ESD_HBM | ESD_MM | PIN_LENGTH_SHORT_PIN | PIN_LENGTH_LONG_PIN | CREATEDAY  ;
{========================================================================================}
 'INA183A1IDBVR' | 'SMLF'    | 'IC'     | 'AL000183000'(!) = ''               | ''               | 'AL000183000' |'SOT23-5_0-95_2-9X1-6XD'| 'IC AMPL(5P)INA183A1IDBVR(SOT23)' | 'TIC'   | 'INA183A1IDBVR' | 'EP(V1)'     | ''        | 'S9S-KIMI' | 'IC'  | ''      | 'TIC_INA183A1IDBVR.PDF' | ''            | ''     | ''  | ''      | ''     | 'NA' | 'na'    | 'na'    | 'na'   | '0 MILS'             | '0 MILS'            | '20200514'
 'INA183A1IDBVR' | 'SMLF'    | 'EMPTY'  | 'AL000183000'(!) = ''               | ''               | 'AL000183000' |'SOT23-5_0-95_2-9X1-6XD'| 'IC AMPL(5P)INA183A1IDBVR(SOT23)' | 'TIC'   | 'INA183A1IDBVR' | 'EP(V1)'     | ''        | 'S9S-KIMI' | 'IC'  | ''      | 'TIC_INA183A1IDBVR.PDF' | ''            | ''     | ''  | ''      | ''     | 'NA' | 'na'    | 'na'    | 'na'   | '0 MILS'             | '0 MILS'            | '20200514'

END_PART

END.

